Altium Designer Pick and Place Locations
C:\Users\<user>\Desktop\WorkNotes\Projects\PTP\TimeCardNPI\HackDesign\WIP\ECAD\Project Outputs for Timingcard_PROJECT\Pick Place for TimeCard-DC-V7_EXP.txt

========================================================================================================================
File Design Information:

Date:       21/11/22
Time:       09:17
Revision:   Not in VersionControl
Variant:    No variations
Units used: mil

Designator Comment             Layer       Footprint                 Center-X(mil) Center-Y(mil) Rotation Description                                                                                                                    
P1         "AUX Sensor"        TopLayer    HDR1X4                    1573.622      -1200.787     180      "Header, 4-Pin"                                                                                                                
R47        DNI_0_5%_1206       TopLayer    RESC3116X65X50ML20T20     3657.480      -1362.205     0        ""                                                                                                                             
J38        39-30-1060          TopLayer    39-30-1060                6492.126      -1779.528     90       "CONN, HDR, 2X3, R/A, 4.2MM, TH, MINI-FIT JR"                                                                                  
R46        DNI_0_5%_1206       TopLayer    RESC3116X65X50ML20T20     3417.323      -1248.032     180      ""                                                                                                                             
R45        0_5%_1206           TopLayer    RESC3116X65X50ML20T20     3649.606      -1248.032     0        ""                                                                                                                             
R44        DNI_0_5%_1206       TopLayer    RESC3116X65X50ML20T20     6480.315      -2602.362     180      ""                                                                                                                             
D19        STPS5L60S           TopLayer    FP-STPS5L60S-MFG          6728.346      -2767.716     270      "DIODE SCHOTTKY 60V 5A SMC"                                                                                                    
D12        STPS5L60S           TopLayer    FP-STPS5L60S-MFG          6728.346      -2275.591     90       "DIODE SCHOTTKY 60V 5A SMC"                                                                                                    
J37        "Single FPGA Conn"  TopLayer    SingleFPGAConn            4309.097      -3085.975     90       ""                                                                                                                             
J36        "Single FPGA Conn"  TopLayer    SingleFPGAConn            3409.043      -2340.449     0        ""                                                                                                                             
J35        "Single FPGA Conn"  TopLayer    SingleFPGAConn            4309.097      -1604.766     270      ""                                                                                                                             
J34        "Single FPGA Conn"  TopLayer    SingleFPGAConn            5283.953      -2340.449     180      ""                                                                                                                             
J31        SA53_Header         TopLayer    SA53_Header               3013.188      -2365.934     180      ""                                                                                                                             
J13        "GNSS Header"       TopLayer    SMTC-TLE-104-01-X-DV      6398.148      -258.362      270      "8-pin GNSS header"                                                                                                            
J6         "GNSS Header"       TopLayer    SMTC-TLE-104-01-X-DV      836.105       -618.599      90       "8-pin GNSS header"                                                                                                            
R43        DNI_49.9R           TopLayer    RESC1608X55X25NL10T15     2452.756      -1271.653     180      "General Purpose Chip Resistor, 49.9 Ohm, +/- 1%, -55 to 155 degC, 0603 (1608 Metric), RoHS, Tape and Reel"                    
R42        DNI_49.9R           TopLayer    RESC1608X55X25NL10T15     2600.503      -1322.773     180      "General Purpose Chip Resistor, 49.9 Ohm, +/- 1%, -55 to 155 degC, 0603 (1608 Metric), RoHS, Tape and Reel"                    
D10        BLUE                TopLayer    FP-LTST-C191TBKT-MFG      403.543       118.110       90       "LED BLUE CLEAR CHIP SMD"                                                                                                      
D9         BLUE                TopLayer    FP-LTST-C191TBKT-MFG      334.646       118.110       90       "LED BLUE CLEAR CHIP SMD"                                                                                                      
D3         BLUE                TopLayer    FP-LTST-C191TBKT-MFG      265.748       118.110       90       "LED BLUE CLEAR CHIP SMD"                                                                                                      
U16        NC7WV125K8X         TopLayer    SOP50P310X90-8N           748.032       -3188.976     180      "Integrated Circuit"                                                                                                           
U12        NC7WV125K8X         TopLayer    SOP50P310X90-8N           757.874       -2125.984     180      "Integrated Circuit"                                                                                                           
U11        NC7WV125K8X         TopLayer    SOP50P310X90-8N           757.874       -2647.638     180      "Integrated Circuit"                                                                                                           
U8         NC7WV125K8X         TopLayer    SOP50P310X90-8N           748.032       -1594.488     180      "Integrated Circuit"                                                                                                           
U6         IS32FL3207          TopLayer    IS32FL3207                1033.465      -1259.842     0        ""                                                                                                                             
R41        4.7K                TopLayer    RESC1608X55X30NL15T15     797.244       -1358.268     0        "Precision Thick Film Chip Resistor, 4.7 KOhm, +/- 1%, -55 to 155 degC, 0603 (1608 Metric), RoHS, Tape and Reel ERJ-3EKF4701V" 
R40        100k                TopLayer    FP-RC0603-0_55-MFG        826.772       -1131.890     270      "RES SMD 100K OHM 1% 1/10W 0603"                                                                                               
R39        "200 OHM"           TopLayer    RESC1608X55X30NL15T15     472.441       -19.685       90       ERJ-3EKF2000V                                                                                                                  
R38        "200 OHM"           TopLayer    RESC1608X55X30NL15T15     403.543       -19.685       90       ERJ-3EKF2000V                                                                                                                  
R36        "200 OHM"           TopLayer    RESC1608X55X30NL15T15     334.646       -19.685       90       ERJ-3EKF2000V                                                                                                                  
R35        "200 OHM"           TopLayer    RESC1608X55X30NL15T15     265.748       -19.685       90       ERJ-3EKF2000V                                                                                                                  
R34        49.9R               TopLayer    RESC1608X55X25NL10T15     568.898       -3169.291     180      "General Purpose Chip Resistor, 49.9 Ohm, +/- 1%, -55 to 155 degC, 0603 (1608 Metric), RoHS, Tape and Reel"                    
R33        49.9R               TopLayer    RESC1608X55X25NL10T15     580.709       -2106.299     180      "General Purpose Chip Resistor, 49.9 Ohm, +/- 1%, -55 to 155 degC, 0603 (1608 Metric), RoHS, Tape and Reel"                    
R32        4.7K                TopLayer    RESC1608X55X30NL15T15     748.032       -3326.772     270      "Precision Thick Film Chip Resistor, 4.7 KOhm, +/- 1%, -55 to 155 degC, 0603 (1608 Metric), RoHS, Tape and Reel ERJ-3EKF4701V" 
R31        4.7K                TopLayer    RESC1608X55X30NL15T15     826.772       -3326.772     270      "Precision Thick Film Chip Resistor, 4.7 KOhm, +/- 1%, -55 to 155 degC, 0603 (1608 Metric), RoHS, Tape and Reel ERJ-3EKF4701V" 
P3         "EXT GPIO"          TopLayer    HDR2X6_CEN                5640.551      89.370        180      "Header, 6-Pin, Dual row"                                                                                                      
J4         1909763-1           TopLayer    TECO-1909763-1_V          412.894       -3169.291     270      "Ultra Miniature Coaxial Connector Jack, 60 V, 50 Ohm, -40 to 90 degC, RoHS, Tape and Reel"                                    
J2         1909763-1           TopLayer    TECO-1909763-1_V          412.894       -2106.299     270      "Ultra Miniature Coaxial Connector Jack, 60 V, 50 Ohm, -40 to 90 degC, RoHS, Tape and Reel"                                    
J3         1909763-1           TopLayer    TECO-1909763-1_V          412.894       -2627.953     270      "Ultra Miniature Coaxial Connector Jack, 60 V, 50 Ohm, -40 to 90 degC, RoHS, Tape and Reel"                                    
J1         1909763-1           TopLayer    TECO-1909763-1_V          412.894       -1574.803     270      "Ultra Miniature Coaxial Connector Jack, 60 V, 50 Ohm, -40 to 90 degC, RoHS, Tape and Reel"                                    
D18        155124M173200       TopLayer    155124M173200             -190.453      -3413.386     90       "LED (Multiple)"                                                                                                               
D17        155124M173200       TopLayer    155124M173200             -190.453      -2885.827     90       "LED (Multiple)"                                                                                                               
D16        155124M173200       TopLayer    155124M173200             -190.453      -2350.394     90       "LED (Multiple)"                                                                                                               
D15        155124M173200       TopLayer    155124M173200             -190.453      -1822.835     90       "LED (Multiple)"                                                                                                               
C40        0.1uF               TopLayer    CAPC1608X87X45ML20T05     826.772       -1259.843     90       C0603X104K5RACAUTO                                                                                                             
C39        0.1uF               TopLayer    CAPC1608X87X45ML20T05     758.445       -1137.402     270      C0603X104K5RACAUTO                                                                                                             
C38        1uF                 TopLayer    FP-C0603C105K3PACTU-MFG   757.874       -1253.937     270      "CAP CER 1UF 25V X5R 0603"                                                                                                     
C33        0.1uF               TopLayer    CAPC1608X87X45ML20T05     5000.000      -1348.913     90       C0603X104K5RACAUTO                                                                                                             
C32        0.1uF               TopLayer    CAPC1608X87X45ML20T05     4844.488      -1376.472     180      C0603X104K5RACAUTO                                                                                                             
R37        10K                 TopLayer    RESC1608X55X30LL15T20     4586.614      -1376.472     180      "Chip Resistor, 10 KOhm, +/- 1%, 0.1 W, -55 to 155 degC, 0603 (1608 Metric), RoHS, Tape and Reel RMCF0603FT10K0"               
U15        RCB-F9T-1           TopLayer    GNSS                      6406.398      -258.362      180      "MOD, GPS"                                                                                                                     
C37        0.1uF               TopLayer    CAPC1608X87X45ML20T05     6474.409      -500.488      0        C0603X104K5RACAUTO                                                                                                             
C36        0.1uF               TopLayer    CAPC1608X87X45ML20T05     6127.664      -140.170      0        C0603X104K5RACAUTO                                                                                                             
C35        10uF                TopLayer    FP-MK212BG-MFG            6476.378      -589.071      180      None                                                                                                                           
C34        10uF                TopLayer    FP-MK212BG-MFG            6131.890      -215.055      180      None                                                                                                                           
D2         8240136             TopLayer    SOT143-4L                 344.488       -2874.016     90       "TVS Diode WE-TVS-HS, VRWM=3.3V"                                                                                               
D1         8240136             TopLayer    SOT143-4L                 344.488       -1797.244     90       "TVS Diode WE-TVS-HS, VRWM=3.3V"                                                                                               
R27        4.7K                TopLayer    RESC1608X55X30NL15T15     3996.063      -1317.417     90       "Precision Thick Film Chip Resistor, 4.7 KOhm, +/- 1%, -55 to 155 degC, 0603 (1608 Metric), RoHS, Tape and Reel ERJ-3EKF4701V" 
R26        4.7K                TopLayer    RESC1608X55X30NL15T15     4055.118      -1317.417     90       "Precision Thick Film Chip Resistor, 4.7 KOhm, +/- 1%, -55 to 155 degC, 0603 (1608 Metric), RoHS, Tape and Reel ERJ-3EKF4701V" 
U10        MAC-SA5X            TopLayer    SA53                      2258.562      -2419.291     180      "MOD, MAC, MAC-SA5X, ATOMIC CLOCK"                                                                                             
R14        4.7K                TopLayer    RESC1608X55X30NL15T15     826.772       -1722.441     270      "Precision Thick Film Chip Resistor, 4.7 KOhm, +/- 1%, -55 to 155 degC, 0603 (1608 Metric), RoHS, Tape and Reel ERJ-3EKF4701V" 
U14        BME280              TopLayer    FP-BME280-MFG             5157.480      -1248.520     0        "SENSOR PRESSURE HUMIDITY TEMP"                                                                                                
U13        BMX160              TopLayer    FP-BMX160-MFG             4862.205      -1248.520     0        "IMU ACCEL/GYRO/MAG"                                                                                                           
U4         DS90LV028AQMA       TopLayer    M08A_L                    2185.039      -1218.992     0        "Automotive LVDS Dual Differential Line Receiver, 8-pin Narrow SOIC"                                                           
U3         DS90LV027AQMA       TopLayer    M08A_N                    2889.764      -1214.465     0        "Automotive LVDS Dual Differential Driver, 8-pin Narrow SOIC"                                                                  
R25        49.9R               TopLayer    RESC1608X55X25NL10T15     570.866       -1574.803     180      "General Purpose Chip Resistor, 49.9 Ohm, +/- 1%, -55 to 155 degC, 0603 (1608 Metric), RoHS, Tape and Reel"                    
R17        4.7K                TopLayer    RESC1608X55X30NL15T15     757.874       -2785.433     270      "Precision Thick Film Chip Resistor, 4.7 KOhm, +/- 1%, -55 to 155 degC, 0603 (1608 Metric), RoHS, Tape and Reel ERJ-3EKF4701V" 
R13        49.9R               TopLayer    RESC1608X55X25NL10T15     2372.047      -1228.835     270      "General Purpose Chip Resistor, 49.9 Ohm, +/- 1%, -55 to 155 degC, 0603 (1608 Metric), RoHS, Tape and Reel"                    
R12        110R                TopLayer    RESC1609X50X30NL10T20     1998.032      -1169.780     270      ""                                                                                                                             
R11        4.7K                TopLayer    RESC1608X55X25LL10T15     2647.638      -1268.205     0        "Chip Resistor, 4.7 KOhm, +/- 1%, 0.1 W, -55 to 155 degC, 0603 (1608 Metric), RoHS, Tape and Reel RC0603FR-074K7L"             
R10        4.7K                TopLayer    RESC1608X55X25LL10T15     2647.638      -1189.465     0        "Chip Resistor, 4.7 KOhm, +/- 1%, 0.1 W, -55 to 155 degC, 0603 (1608 Metric), RoHS, Tape and Reel RC0603FR-074K7L"             
C31        0.1uF               TopLayer    CAPC1608X87X45ML20T05     5285.433      -1148.126     270      C0603X104K5RACAUTO                                                                                                             
C30        0.1uF               TopLayer    CAPC1608X87X45ML20T05     5159.449      -1120.567     180      C0603X104K5RACAUTO                                                                                                             
C29        0.1uF               TopLayer    CAPC1608X87X45ML20T05     679.134       -3326.772     270      C0603X104K5RACAUTO                                                                                                             
C28        0.1uF               TopLayer    CAPC1608X87X45ML20T05     688.976       -2244.094     270      C0603X104K5RACAUTO                                                                                                             
C27        0.1uF               TopLayer    CAPC1608X87X45ML20T05     688.976       -2785.433     270      C0603X104K5RACAUTO                                                                                                             
C26        0.1uF               TopLayer    CAPC1608X87X45ML20T05     679.134       -1722.441     270      C0603X104K5RACAUTO                                                                                                             
C24        0.1uF               TopLayer    CAPC1608X87X45ML20T05     2440.945      -1179.622     270      C0603X104K5RACAUTO                                                                                                             
C23        0.1uF               TopLayer    CAPC1608X87X45ML20T05     2667.323      -1120.567     0        C0603X104K5RACAUTO                                                                                                             
AN1        901-143-6RFX        TopLayer    AMPH-901-143-6RFX_V       -84.645       -1573.323     180      "Coaxial connector, 50 Ohm, -65 to 165 degC, 5-Pin THD, RoHS, Bulk"                                                            
AN3        901-143-6RFX        TopLayer    AMPH-901-143-6RFX_V       -84.646       -2636.299     180      "Coaxial connector, 50 Ohm, -65 to 165 degC, 5-Pin THD, RoHS, Bulk"                                                            
AN2        901-143-6RFX        TopLayer    AMPH-901-143-6RFX_V       -84.646       -2104.803     180      "Coaxial connector, 50 Ohm, -65 to 165 degC, 5-Pin THD, RoHS, Bulk"                                                            
AN4        901-143-6RFX        TopLayer    AMPH-901-143-6RFX_V       -84.645       -3167.811     180      "Coaxial connector, 50 Ohm, -65 to 165 degC, 5-Pin THD, RoHS, Bulk"                                                            
U7         AT24MAC402-STUM-T   TopLayer    FP-5TS1-IPC_C             4606.299      -1258.362     270      "IC EEPROM 2K I2C 1MHZ SOT23-5"                                                                                                
C25        0.1uF               TopLayer    CAPC1608X87X45ML20T05     4478.346      -1258.362     270      C0603X104K5RACAUTO                                                                                                             
R16        4.7K                TopLayer    RESC1608X55X30NL15T15     836.614       -2785.433     270      "Precision Thick Film Chip Resistor, 4.7 KOhm, +/- 1%, -55 to 155 degC, 0603 (1608 Metric), RoHS, Tape and Reel ERJ-3EKF4701V" 
R15        4.7K                TopLayer    RESC1608X55X30NL15T15     748.032       -1722.441     270      "Precision Thick Film Chip Resistor, 4.7 KOhm, +/- 1%, -55 to 155 degC, 0603 (1608 Metric), RoHS, Tape and Reel ERJ-3EKF4701V" 
R5         ERJ-3EKF2612V       TopLayer    RESC1608X50N              5738.134      -1172.055     0        "RES, 26.1K, 1%, 1/10W, TF, 0603"                                                                                              
U9         RCB-F9T             TopLayer    GNSS                      827.855       -618.598      0        "MOD, GPS"                                                                                                                     
U5         HTST-105-01-L-DV-A  TopLayer    SAMTEC_HTST-105-01-L-DV-A 5892.913      -3300.394     0        "CONN, HDR, 2X5, VERT, 0.1IN  SHROUDED, SMT, HTSH SERIES"                                                                      
U2         MP1482DS-LF         TopLayer    SOIC127P600X175-8N        5593.134      -1304.055     90       "IC, DC/DC, MP1482DS, >4.75VIN, 0.923-15V OUT, SOIC8"                                                                          
U1         MP1482DS-LF         TopLayer    SOIC127P600X175-8N        5684.189      -2334.055     90       "IC, DC/DC, MP1482DS, >4.75VIN, 0.923-15V OUT, SOIC8"                                                                          
R30        4.7K                TopLayer    RESC1608X55X30NL15T15     757.874       -2244.094     270      "Precision Thick Film Chip Resistor, 4.7 KOhm, +/- 1%, -55 to 155 degC, 0603 (1608 Metric), RoHS, Tape and Reel ERJ-3EKF4701V" 
R29        4.7K                TopLayer    RESC1608X55X30NL15T15     826.772       -2244.095     270      "Precision Thick Film Chip Resistor, 4.7 KOhm, +/- 1%, -55 to 155 degC, 0603 (1608 Metric), RoHS, Tape and Reel ERJ-3EKF4701V" 
R28        49.9R               TopLayer    RESC1608X55X25NL10T15     580.709       -2627.953     180      "General Purpose Chip Resistor, 49.9 Ohm, +/- 1%, -55 to 155 degC, 0603 (1608 Metric), RoHS, Tape and Reel"                    
R24        ERJ-2GE0R00X        TopLayer    RESC1005X04N              2769.685      -3561.512     270      "RES, 0. OHM, 1%, 1/16W, TF, AEC-Q200, 0402"                                                                                   
R23        ERJ-2GE0R00X        TopLayer    RESC1005X04N              2218.504      -3561.512     270      "RES, 0. OHM, 1%, 1/16W, TF, AEC-Q200, 0402"                                                                                   
R22        ERJ-3EKF4701V       TopLayer    RESC1608X50N              1134.252      -2636.315     180      "RES, 4.7K, 1%, 1/10W, TF, 0603"                                                                                               
R21        CRCW080533R0FKEA    TopLayer    RESC2012X50N              6370.079      -3429.134     270      "RES, 33 OHM, 1%, 1/8W, TF, 0805"                                                                                              
R20        CRCW080533R0FKEA    TopLayer    RESC2012X50N              6551.181      -3425.197     270      "RES, 33 OHM, 1%, 1/8W, TF, 0805"                                                                                              
R19        CRCW080533R0FKEA    TopLayer    RESC2012X50N              5361.624      -3478.796     0        "RES, 33 OHM, 1%, 1/8W, TF, 0805"                                                                                              
R18        CRCW080533R0FKEA    TopLayer    RESC2012X50N              5365.561      -3317.379     0        "RES, 33 OHM, 1%, 1/8W, TF, 0805"                                                                                              
R9         ERJ-3EKF2201V       TopLayer    RESC1608X50N              5639.275      -1053.150     180      "RES, 2.2K, 1%, 1/10W, TF, 0603"                                                                                               
R8         ERJ-3EKF2201V       TopLayer    RESC1608X50N              5734.740      -2068.898     180      "RES, 2.2K, 1%, 1/10W, TF, 0603"                                                                                               
R7         ERJ-3EKF1002V       TopLayer    RESC1608X50N              5737.701      -1387.795     90       "RES, 10K, 1%, 1/10W, TF, 0603"                                                                                                
R6         ERJ-3EKF1002V       TopLayer    RESC1608X50N              5821.354      -2305.118     90       "RES, 10K, 1%, 1/10W, TF, 0603"                                                                                                
R4         ERJ-3EKF4702V       TopLayer    RESC1608X50N              5824.189      -2199.055     90       "RES, 47K, 1%, 1/10W, TF, 0603"                                                                                                
R3         ERJ-3EKF4702V       TopLayer    RESC1608X50N              5433.134      -1284.055     180      "RES, 47K, 1%, 1/10W, TF, 0603"                                                                                                
R2         ERJ-3EKF4702V       TopLayer    RESC1608X50N              5524.189      -2319.055     180      "RES, 47K, 1%, 1/10W, TF, 0603"                                                                                                
R1         ERJ-3EKF2000V       TopLayer    RESC1608X50N              6210.142      -1183.071     0        "RES, 200 OHM, 1%, 1/10W, TF, 0603"                                                                                            
P2         PCIex4              TopLayer    PCIE_4LANE_EDGE           2161.417      -4004.518     0        "PCIE x4 Edge Connector,OrCAD Symbol,NC"                                                                                       
L2         PM124SH-100M-RC     TopLayer    IND_PM124SH               5818.898      -1736.220     180      "IND, PWR, 10.uH, 20%, 4A, 0.04DCR, 12.5X12.5MM, SHLD"                                                                         
L1         PM124SH-100M-RC     TopLayer    IND_PM124SH               5989.189      -2749.055     180      "IND, PWR, 10.uH, 20%, 4A, 0.04DCR, 12.5X12.5MM, SHLD"                                                                         
F1         FUSE_0603_2.00A     TopLayer    FUSM1608X60N              6515.748      -2496.063     180      "FUSE SLOW 2.00A 32V M 0603"                                                                                                   
D14        155124M173200       TopLayer    155124M173200             -190.453      -1084.646     90       "LED (Multiple)"                                                                                                               
D13        155124M173200       TopLayer    155124M173200             -190.453      -651.575      90       "LED (Multiple)"                                                                                                               
D11        BLUE                TopLayer    FP-LTST-C191TBKT-MFG      472.441       118.110       90       "LED BLUE CLEAR CHIP SMD"                                                                                                      
D8         BAT54SW             TopLayer    SOT65P210X110-3N          6370.079      -3248.032     270      "DIO, SCHOTTKY, BAT54S, DUAL SERIES, 30V, 200MA, SC-70"                                                                        
D7         BAT54SW             TopLayer    SOT65P210X110-3N          6557.087      -3249.016     270      "DIO, SCHOTTKY, BAT54S, DUAL SERIES, 30V, 200MA, SC-70"                                                                        
D6         BAT54SW             TopLayer    SOT65P210X110-3N          5195.286      -3478.796     0        "DIO, SCHOTTKY, BAT54S, DUAL SERIES, 30V, 200MA, SC-70"                                                                        
D5         BAT54SW             TopLayer    SOT65P210X110-3N          5196.270      -3317.379     0        "DIO, SCHOTTKY, BAT54S, DUAL SERIES, 30V, 200MA, SC-70"                                                                        
D4         RED                 TopLayer    DIOM1608X06N              6208.661      -1244.094     180      "LED, RED, SML-LX0603, 635NM, 2V, 20MA, 0603"                                                                                  
C63        0.1uF               TopLayer    CAPC1608X87X45ML20T05     3481.060      -1014.822     270      C0603X104K5RACAUTO                                                                                                             
C62        CAP_0805_10UF_25V   TopLayer    CAPC2012X14N              3574.803      -1003.937     90       "CAP, CER, 10.UF, 25V, 10%, X5R, 0805"                                                                                         
C61        0.1uF               TopLayer    CAPC1608X87X45ML20T05     984.252       -953.244      90       C0603X104K5RACAUTO                                                                                                             
C60        10uF                TopLayer    FP-MK212BG-MFG            895.669       -943.402      270      None                                                                                                                           
C59        0.1uF               TopLayer    CAPC1608X87X45ML20T05     1141.732      -766.236      90       C0603X104K5RACAUTO                                                                                                             
C58        10uF                TopLayer    FP-MK212BG-MFG            1230.315      -760.331      270      None                                                                                                                           
C53        CAP_0402_0.1UF_50V  BottomLayer CAPC1005X06N              2734.410      -3806.000     90       "CAP, CER, 0.1UF, 50V, 10%, X7R, AEC-Q200, 0402"                                                                               
C52        CAP_0402_0.1UF_50V  BottomLayer CAPC1005X06N              2694.410      -3806.000     90       "CAP, CER, 0.1UF, 50V, 10%, X7R, AEC-Q200, 0402"                                                                               
C51        CAP_0402_0.1UF_50V  BottomLayer CAPC1005X06N              2569.410      -3806.000     90       "CAP, CER, 0.1UF, 50V, 10%, X7R, AEC-Q200, 0402"                                                                               
C50        CAP_0402_0.1UF_50V  BottomLayer CAPC1005X06N              2534.410      -3806.000     90       "CAP, CER, 0.1UF, 50V, 10%, X7R, AEC-Q200, 0402"                                                                               
C49        CAP_0402_0.1UF_50V  BottomLayer CAPC1005X06N              2419.410      -3806.000     90       "CAP, CER, 0.1UF, 50V, 10%, X7R, AEC-Q200, 0402"                                                                               
C48        CAP_0402_0.1UF_50V  BottomLayer CAPC1005X06N              2379.410      -3806.000     90       "CAP, CER, 0.1UF, 50V, 10%, X7R, AEC-Q200, 0402"                                                                               
C47        CAP_0402_0.1UF_50V  BottomLayer CAPC1005X06N              2226.410      -3806.000     90       "CAP, CER, 0.1UF, 50V, 10%, X7R, AEC-Q200, 0402"                                                                               
C46        CAP_0402_0.1UF_50V  BottomLayer CAPC1005X06N              2183.410      -3806.000     90       "CAP, CER, 0.1UF, 50V, 10%, X7R, AEC-Q200, 0402"                                                                               
C45        CAP_0402_0.1UF_50V  BottomLayer CAPC1005X06N              2104.410      -3806.000     90       "CAP, CER, 0.1UF, 50V, 10%, X7R, AEC-Q200, 0402"                                                                               
C44        CAP_0402_0.1UF_50V  BottomLayer CAPC1005X06N              2064.410      -3806.000     90       "CAP, CER, 0.1UF, 50V, 10%, X7R, AEC-Q200, 0402"                                                                               
C22        0.033uF             TopLayer    CAPC1608X90X35NL10T15     5638.134      -1114.055     0        GCM188R71H333KA55D                                                                                                             
C21        0.1uF               TopLayer    CAPC1608X87X45ML20T05     5448.134      -1174.055     270      C0603X104K5RACAUTO                                                                                                             
C20        0.033uF             TopLayer    CAPC1608X90X35NL10T15     5734.189      -2129.055     0        GCM188R71H333KA55D                                                                                                             
C19        0.1uF               TopLayer    CAPC1608X87X45ML20T05     5544.189      -2194.055     270      C0603X104K5RACAUTO                                                                                                             
C18        0.1uF               TopLayer    CAPC1608X87X45ML20T05     5864.189      -2409.055     90       C0603X104K5RACAUTO                                                                                                             
C17        0.1uF               TopLayer    CAPC1608X87X45ML20T05     5919.189      -2409.055     90       C0603X104K5RACAUTO                                                                                                             
C16        0.1uF               TopLayer    CAPC1608X87X45ML20T05     5969.189      -2409.055     90       C0603X104K5RACAUTO                                                                                                             
C15        0.1uF               TopLayer    CAPC1608X87X45ML20T05     6029.189      -2409.055     90       C0603X104K5RACAUTO                                                                                                             
C14        CAP_0805_10UF_25V   TopLayer    CAPC2012X14N              6109.189      -2404.055     270      "CAP, CER, 10.UF, 25V, 10%, X5R, 0805"                                                                                         
C13        CAP_0805_10UF_25V   TopLayer    CAPC2012X14N              6219.189      -2404.055     270      "CAP, CER, 10.UF, 25V, 10%, X5R, 0805"                                                                                         
C12        0.1uF               TopLayer    CAPC1608X87X45ML20T05     5950.299      -1391.733     90       C0603X104K5RACAUTO                                                                                                             
C11        0.1uF               TopLayer    CAPC1608X87X45ML20T05     5883.370      -1391.733     90       C0603X104K5RACAUTO                                                                                                             
C10        0.1uF               TopLayer    CAPC1608X87X45ML20T05     5812.504      -1391.733     90       C0603X104K5RACAUTO                                                                                                             
C9         0.1uF               TopLayer    CAPC1608X87X45ML20T05     6017.228      -1391.733     90       C0603X104K5RACAUTO                                                                                                             
C8         CAP_0805_10UF_25V   TopLayer    CAPC2012X14N              6229.827      -1411.417     0        "CAP, CER, 10.UF, 25V, 10%, X5R, 0805"                                                                                         
C7         CAP_0805_10UF_25V   TopLayer    CAPC2012X14N              6229.827      -1324.803     0        "CAP, CER, 10.UF, 25V, 10%, X5R, 0805"                                                                                         
C6         CAP_0805_10UF_25V   TopLayer    CAPC2012X14N              5509.189      -2409.055     180      "CAP, CER, 10.UF, 25V, 10%, X5R, 0805"                                                                                         
C5         CAP_0805_10UF_25V   TopLayer    CAPC2012X14N              5423.134      -1384.055     180      "CAP, CER, 10.UF, 25V, 10%, X5R, 0805"                                                                                         
C4         CAP_0603_0.01UF_50V TopLayer    CAPC1608X10N              5654.189      -2549.055     0        "CAP, CER, 0.01UF, 50V, 10%, X7R, 0603"                                                                                        
C3         CAP_0603_0.01UF_50V TopLayer    CAPC1608X10N              5484.252      -1539.370     270      "CAP, CER, 0.01UF, 50V, 10%, X7R, 0603"                                                                                        
C2         0.1uF               TopLayer    CAPC1608X87X45ML20T05     6397.638      -2389.764     270      C0603X104K5RACAUTO                                                                                                             
C1         CAP_0805_10UF_25V   TopLayer    CAPC2012X14N              6484.252      -2377.953     90       "CAP, CER, 10.UF, 25V, 10%, X5R, 0805"                                                                                         
